# S9S_MB_2U (Grand Teton) — schematic netlist excerpt (pin names and nets, part order shuffled) for the footprints in the layout excerpt that follows; sources: Cadence DE-HDL packaged netlist, KiCad conversion of 03242023_DA0F0TMBIJ0_F0T_Motherboard_J_brd_V01_OCP.brd

PC620  Q_CAPP  560UF 2.5V 20% OSCON  pkg THLF  page 271 : A = PVCCFA_EHV_FIVRA_CPU0 ; B = GND

U239  74LVC1G126SE7  74LVC1G126SE-7 IC  pkg SOT353_0-65_2X1-25  page 190
  OE  = PU_BUFFER_HDD_ACTIVITY
  A  = LED_HDD_ACTIVITY_N
  GND  = GND
  Y  = LED_HDD_ACTIVITY_B_N
  VCC  = P3V3_AUX

R1126  Q_RES  1K 1% CHIP  pkg 0402LF  page 158 : A = PD_SMB_OCP1_HP_ADD1 ; B = GND

(kicad_pcb
	(version 20260206)
	(generator "pcbnew")
	(generator_version "10.0")
	(general
		(thickness 1.6)
		(legacy_teardrops no)
	)
	(paper "A4")
	(title_block
		(title "03242023_DA0F0TMBIJ0_F0T_Motherboard_J_brd_V01_OCP.brd")
		(comment 1 "Grand Teton / footprints 1849-1851 of 6105")
	)
	(layers
		(0 "F.Cu" signal "TOP")
		(4 "In1.Cu" signal "GND")
		(6 "In2.Cu" signal "IN1")
		(8 "In3.Cu" signal "GND1")
		(10 "In4.Cu" signal "IN2")
		(12 "In5.Cu" signal "GND2")
		(14 "In6.Cu" signal "IN3")
		(16 "In7.Cu" signal "GND3")
		(18 "In8.Cu" signal "VCC")
		(20 "In9.Cu" signal "VCC1")
		(22 "In10.Cu" signal "GND4")
		(24 "In11.Cu" signal "IN4")
		(26 "In12.Cu" signal "GND5")
		(28 "In13.Cu" signal "IN5")
		(30 "In14.Cu" signal "GND6")
		(32 "In15.Cu" signal "IN6")
		(34 "In16.Cu" signal "GND7")
		(2 "B.Cu" signal "BOTTOM")
		(9 "F.Adhes" user "F.Adhesive")
		(11 "B.Adhes" user "B.Adhesive")
		(13 "F.Paste" user "Package Geometry/Pastemask Top")
		(15 "B.Paste" user "Package Geometry/Pastemask Bottom")
		(5 "F.SilkS" user "Ref Des/Silkscreen Top")
		(7 "B.SilkS" user "Ref Des/Silkscreen Bottom")
		(1 "F.Mask" user "Board Geometry/Soldermask Top")
		(3 "B.Mask" user "Board Geometry/Soldermask Bottom")
		(17 "Dwgs.User" user "User.Drawings")
		(19 "Cmts.User" user "User.Comments")
		(21 "Eco1.User" user "User.Eco1")
		(23 "Eco2.User" user "User.Eco2")
		(25 "Edge.Cuts" user "Board Geometry/Outline")
		(27 "Margin" user)
		(31 "F.CrtYd" user "Package Geometry/Place Bound Top")
		(29 "B.CrtYd" user "Package Geometry/Place Bound Bottom")
		(35 "F.Fab" user "Ref Des/Assembly Top")
		(33 "B.Fab" user "Ref Des/Assembly Bottom")
	)
	(footprint ""
		(layer "F.Cu")
		(at 149.25421 -42.488104)
		(property "Reference" "U239"
			(at -4.5593 -1.791208 0)
			(unlocked yes)
			(layer "F.SilkS")
			(effects
				(font
					(size 0.7874 0.5842)
					(thickness 0.1524)
				)
				(justify left)
			)
		)
		(property "Value" ""
			(at 0 0 0)
			(layer "F.Fab")
			(effects
				(font
					(size 1.27 1.27)
				)
			)
		)
		(duplicate_pad_numbers_are_jumpers no)
		(fp_line
			(start -1.400048 1.100074)
			(end -1.400048 -1.100074)
			(stroke
				(width 0.1524)
				(type default)
			)
			(layer "F.SilkS")
		)
		(fp_line
			(start 1.400048 -1.100074)
			(end -1.400048 -1.100074)
			(stroke
				(width 0.1524)
				(type default)
			)
			(layer "F.SilkS")
		)
		(fp_line
			(start 1.400048 -1.100074)
			(end 1.400048 1.100074)
			(stroke
				(width 0.1524)
				(type default)
			)
			(layer "F.SilkS")
		)
		(fp_line
			(start 1.400048 1.100074)
			(end -1.400048 1.100074)
			(stroke
				(width 0.1524)
				(type default)
			)
			(layer "F.SilkS")
		)
		(fp_poly
			(pts
				(xy -1.054608 -1.316482) (xy -1.562608 -2.332482) (xy -0.546608 -2.332482)
			)
			(stroke
				(width 0)
				(type default)
			)
			(fill yes)
			(layer "F.SilkS")
		)
		(fp_line
			(start -0.674878 -1.100074)
			(end 0.674878 -1.100074)
			(stroke
				(width 0.1)
				(type default)
			)
			(layer "F.Fab")
		)
		(fp_line
			(start -0.674878 1.100074)
			(end -0.674878 -1.100074)
			(stroke
				(width 0.1)
				(type default)
			)
			(layer "F.Fab")
		)
		(fp_line
			(start 0.674878 -1.100074)
			(end 0.674878 1.100074)
			(stroke
				(width 0.1)
				(type default)
			)
			(layer "F.Fab")
		)
		(fp_line
			(start 0.674878 1.100074)
			(end -0.674878 1.100074)
			(stroke
				(width 0.1)
				(type default)
			)
			(layer "F.Fab")
		)
		(fp_poly
			(pts
				(xy -1.590548 -0.649986) (xy -2.606548 -1.157986) (xy -2.606548 -0.141986)
			)
			(stroke
				(width 0)
				(type default)
			)
			(fill yes)
			(layer "F.Fab")
		)
		(pad "1" smd rect
			(at -0.94996 -0.649986 270)
			(size 0.4318 0.6096)
			(layers "F.Cu" "F.Mask" "F.Paste")
			(net "PU_BUFFER_HDD_ACTIVITY")
		)
		(pad "2" smd rect
			(at -0.94996 0 270)
			(size 0.4318 0.6096)
			(layers "F.Cu" "F.Mask" "F.Paste")
			(net "LED_HDD_ACTIVITY_N")
		)
		(pad "3" smd rect
			(at -0.94996 0.649986 270)
			(size 0.4318 0.6096)
			(layers "F.Cu" "F.Mask" "F.Paste")
			(net "GND")
		)
		(pad "4" smd rect
			(at 0.94996 0.649986 270)
			(size 0.4318 0.6096)
			(layers "F.Cu" "F.Mask" "F.Paste")
			(net "LED_HDD_ACTIVITY_B_N")
		)
		(pad "5" smd rect
			(at 0.94996 -0.649986 270)
			(size 0.4318 0.6096)
			(layers "F.Cu" "F.Mask" "F.Paste")
			(net "P3V3_AUX")
		)
	)
	(footprint ""
		(layer "F.Cu")
		(at 293.497 -346.700348)
		(property "Reference" "PC620"
			(at 0 0 0)
			(layer "F.SilkS")
			(hide yes)
			(effects
				(font
					(size 1.27 1.27)
				)
			)
		)
		(property "Value" ""
			(at 0 0 0)
			(layer "F.Fab")
			(effects
				(font
					(size 1.27 1.27)
				)
			)
		)
		(duplicate_pad_numbers_are_jumpers no)
		(fp_line
			(start 2.750058 0.999998)
			(end -2.750058 0.999998)
			(stroke
				(width 0.1524)
				(type default)
			)
			(layer "F.SilkS")
		)
		(fp_circle
			(center 0 0.999998)
			(end 2.750058 0.999998)
			(stroke
				(width 0.1524)
				(type default)
			)
			(fill no)
			(layer "F.SilkS")
		)
		(fp_poly
			(pts
				(arc
					(start 2.750058 0.999998)
					(mid 0 3.750056)
					(end -2.750058 0.999998)
				)
			)
			(stroke
				(width 0)
				(type default)
			)
			(fill yes)
			(layer "F.SilkS")
		)
		(fp_circle
			(center 0 0.999998)
			(end 2.750058 0.999998)
			(stroke
				(width 0.1)
				(type default)
			)
			(fill no)
			(layer "F.Fab")
		)
		(pad "1" thru_hole rect
			(at 0 0)
			(size 1.5748 1.5748)
			(drill 1.0668)
			(layers "*.Cu" "*.Mask")
			(remove_unused_layers no)
			(net "PVCCFA_EHV_FIVRA_CPU0")
			(clearance 0)
			(padstack
				(mode front_inner_back)
				(layer "Inner"
					(shape circle)
					(size 1.5748 1.5748)
					(clearance 0)
				)
				(layer "B.Cu"
					(shape rect)
					(size 1.5748 1.5748)
					(clearance 0)
				)
			)
		)
		(pad "2" thru_hole circle
			(at 0 1.999996)
			(size 1.5748 1.5748)
			(drill 1.0668)
			(layers "*.Cu" "*.Mask")
			(remove_unused_layers no)
			(net "GND")
			(clearance 0)
		)
	)
	(footprint ""
		(layer "F.Cu")
		(at 449.973954 -118.336822 180)
		(property "Reference" "R1126"
			(at 0 0 180)
			(layer "F.SilkS")
			(hide yes)
			(effects
				(font
					(size 1.27 1.27)
				)
			)
		)
		(property "Value" ""
			(at 0 0 180)
			(layer "F.Fab")
			(effects
				(font
					(size 1.27 1.27)
				)
			)
		)
		(duplicate_pad_numbers_are_jumpers no)
		(fp_line
			(start 0.7874 0.4064)
			(end -0.7874 0.4064)
			(stroke
				(width 0.1524)
				(type default)
			)
			(layer "F.SilkS")
		)
		(fp_line
			(start 0.7874 -0.4064)
			(end 0.7874 0.4064)
			(stroke
				(width 0.1524)
				(type default)
			)
			(layer "F.SilkS")
		)
		(fp_line
			(start -0.7874 0.4064)
			(end -0.7874 -0.4064)
			(stroke
				(width 0.1524)
				(type default)
			)
			(layer "F.SilkS")
		)
		(fp_line
			(start -0.7874 -0.4064)
			(end 0.7874 -0.4064)
			(stroke
				(width 0.1524)
				(type default)
			)
			(layer "F.SilkS")
		)
		(fp_line
			(start 0.67945 0.3048)
			(end 0.120396 0.3048)
			(stroke
				(width 0.1)
				(type default)
			)
			(layer "F.Fab")
		)
		(fp_line
			(start 0.67945 -0.3048)
			(end 0.67945 0.3048)
			(stroke
				(width 0.1)
				(type default)
			)
			(layer "F.Fab")
		)
		(fp_line
			(start 0.12065 -0.2794)
			(end 0.12065 -0.3048)
			(stroke
				(width 0.1)
				(type default)
			)
			(layer "F.Fab")
		)
		(fp_line
			(start 0.12065 -0.3048)
			(end 0.67945 -0.3048)
			(stroke
				(width 0.1)
				(type default)
			)
			(layer "F.Fab")
		)
		(fp_line
			(start 0.120396 0.3048)
			(end 0.120396 0.2794)
			(stroke
				(width 0.1)
				(type default)
			)
			(layer "F.Fab")
		)
		(fp_line
			(start 0.120396 0.2794)
			(end -0.12065 0.2794)
			(stroke
				(width 0.1)
				(type default)
			)
			(layer "F.Fab")
		)
		(fp_line
			(start -0.12065 0.3048)
			(end -0.67945 0.3048)
			(stroke
				(width 0.1)
				(type default)
			)
			(layer "F.Fab")
		)
		(fp_line
			(start -0.12065 0.2794)
			(end -0.12065 0.3048)
			(stroke
				(width 0.1)
				(type default)
			)
			(layer "F.Fab")
		)
		(fp_line
			(start -0.12065 -0.2794)
			(end 0.12065 -0.2794)
			(stroke
				(width 0.1)
				(type default)
			)
			(layer "F.Fab")
		)
		(fp_line
			(start -0.12065 -0.305054)
			(end -0.12065 -0.2794)
			(stroke
				(width 0.1)
				(type default)
			)
			(layer "F.Fab")
		)
		(fp_line
			(start -0.67945 0.3048)
			(end -0.67945 -0.305054)
			(stroke
				(width 0.1)
				(type default)
			)
			(layer "F.Fab")
		)
		(fp_line
			(start -0.67945 -0.305054)
			(end -0.12065 -0.305054)
			(stroke
				(width 0.1)
				(type default)
			)
			(layer "F.Fab")
		)
		(pad "1" smd circle
			(at -0.40005 0 180)
			(size 0 0)
			(layers "F.Cu" "F.Mask" "F.Paste")
			(net "PD_SMB_OCP1_HP_ADD1")
		)
		(pad "2" smd circle
			(at 0.40005 0 180)
			(size 0 0)
			(layers "F.Cu" "F.Mask" "F.Paste")
			(net "GND")
		)
	)
)
